(kicad_pcb
	(version 20260206)
	(generator "pcbnew")
	(generator_version "10.0")
	(general
		(thickness 1.6)
		(legacy_teardrops no)
	)
	(paper "A4")
	(title_block
		(title "Wiwynn_Tioga_Pass_MB.brd")
		(comment 1 "Tioga Pass / footprints 2374-2380 of 4770")
	)
	(layers
		(0 "F.Cu" signal "TOP")
		(4 "In1.Cu" signal "L2GND")
		(6 "In2.Cu" signal "L3")
		(8 "In3.Cu" signal "L4GND")
		(10 "In4.Cu" signal "L5")
		(12 "In5.Cu" signal "L6GND")
		(14 "In6.Cu" signal "L7VCC")
		(16 "In7.Cu" signal "L8VCC")
		(18 "In8.Cu" signal "L9GND")
		(20 "In9.Cu" signal "L10")
		(22 "In10.Cu" signal "L11GND")
		(24 "In11.Cu" signal "L12")
		(26 "In12.Cu" signal "L13GND")
		(2 "B.Cu" signal "BOTTOM")
		(9 "F.Adhes" user "F.Adhesive")
		(11 "B.Adhes" user "B.Adhesive")
		(13 "F.Paste" user "Package Geometry/Pastemask Top")
		(15 "B.Paste" user "Package Geometry/Pastemask Bottom")
		(5 "F.SilkS" user "Ref Des/Silkscreen Top")
		(7 "B.SilkS" user "Ref Des/Silkscreen Bottom")
		(1 "F.Mask" user "Board Geometry/Soldermask Top")
		(3 "B.Mask" user "Board Geometry/Soldermask Bottom")
		(17 "Dwgs.User" user "User.Drawings")
		(19 "Cmts.User" user "User.Comments")
		(21 "Eco1.User" user "User.Eco1")
		(23 "Eco2.User" user "User.Eco2")
		(25 "Edge.Cuts" user "Board Geometry/Outline")
		(27 "Margin" user)
		(31 "F.CrtYd" user "Package Geometry/Place Bound Top")
		(29 "B.CrtYd" user "Package Geometry/Place Bound Bottom")
		(35 "F.Fab" user "Ref Des/Assembly Top")
		(33 "B.Fab" user "Ref Des/Assembly Bottom")
	)
	(footprint ""
		(layer "B.Cu")
		(at 20.447 -69.85 180)
		(property "Reference" "R9P29"
			(at 0 0 0)
			(layer "B.SilkS")
			(hide yes)
			(effects
				(font
					(size 1.27 1.27)
				)
				(justify mirror)
			)
		)
		(property "Value" ""
			(at 0 0 0)
			(layer "B.Fab")
			(effects
				(font
					(size 1.27 1.27)
				)
				(justify mirror)
			)
		)
		(duplicate_pad_numbers_are_jumpers no)
		(fp_poly
			(pts
				(xy 0.2794 -0.1016) (xy -0.2794 -0.1016) (xy -0.2794 0.9906) (xy 0.2794 0.9906)
			)
			(stroke
				(width 0)
				(type default)
			)
			(fill no)
			(layer "B.CrtYd")
		)
		(fp_line
			(start 0.2794 0.9906)
			(end -0.2794 0.9906)
			(stroke
				(width 0.1)
				(type default)
			)
			(layer "B.Fab")
		)
		(fp_line
			(start 0.2794 -0.1016)
			(end 0.2794 0.9906)
			(stroke
				(width 0.1)
				(type default)
			)
			(layer "B.Fab")
		)
		(fp_line
			(start -0.2794 0.9906)
			(end -0.2794 -0.1016)
			(stroke
				(width 0.1)
				(type default)
			)
			(layer "B.Fab")
		)
		(fp_line
			(start -0.2794 -0.1016)
			(end 0.2794 -0.1016)
			(stroke
				(width 0.1)
				(type default)
			)
			(layer "B.Fab")
		)
		(pad "1" smd rect
			(at 0 0)
			(size 0.508 0.508)
			(layers "B.Cu" "B.Mask" "B.Paste")
			(net "P12V_PSU")
		)
		(pad "2" smd rect
			(at 0 0.889)
			(size 0.508 0.508)
			(layers "B.Cu" "B.Mask" "B.Paste")
			(net "A_HSC_UV")
		)
		(zone
			(layer "B.Cu")
			(hatch none 0.5)
			(connect_pads
				(clearance 0)
			)
			(min_thickness 0.25)
			(keepout
				(tracks not_allowed)
				(vias allowed)
				(pads allowed)
				(copperpour not_allowed)
				(footprints allowed)
			)
			(placement
				(enabled no)
				(sheetname "")
			)
			(fill
				(thermal_gap 0.5)
				(thermal_bridge_width 0.5)
				(island_removal_mode 0)
			)
			(polygon
				(pts
					(xy 20.193 -70.485) (xy 20.701 -70.485) (xy 20.701 -70.104) (xy 20.193 -70.104)
				)
			)
		)
		(zone
			(layer "B.Cu")
			(hatch none 0.5)
			(connect_pads
				(clearance 0)
			)
			(min_thickness 0.25)
			(keepout
				(tracks allowed)
				(vias not_allowed)
				(pads allowed)
				(copperpour not_allowed)
				(footprints allowed)
			)
			(placement
				(enabled no)
				(sheetname "")
			)
			(fill
				(thermal_gap 0.5)
				(thermal_bridge_width 0.5)
				(island_removal_mode 0)
			)
			(polygon
				(pts
					(xy 20.193 -70.104) (xy 20.701 -70.104) (xy 20.701 -70.485) (xy 20.193 -70.485)
				)
			)
		)
	)
	(footprint ""
		(layer "B.Cu")
		(at 385.217924 -24.885904 90)
		(property "Reference" "C2T20"
			(at 0 0 90)
			(layer "B.SilkS")
			(hide yes)
			(effects
				(font
					(size 1.27 1.27)
				)
				(justify mirror)
			)
		)
		(property "Value" ""
			(at 0 0 90)
			(layer "B.Fab")
			(effects
				(font
					(size 1.27 1.27)
				)
				(justify mirror)
			)
		)
		(duplicate_pad_numbers_are_jumpers no)
		(fp_poly
			(pts
				(xy -0.3048 -0.1016) (xy -0.3048 0.9906) (xy 0.3048 0.9906) (xy 0.3048 -0.1016)
			)
			(stroke
				(width 0)
				(type default)
			)
			(fill no)
			(layer "B.CrtYd")
		)
		(fp_line
			(start 0.3048 -0.1016)
			(end 0.3048 0.9906)
			(stroke
				(width 0.1)
				(type default)
			)
			(layer "B.Fab")
		)
		(fp_line
			(start -0.3048 -0.1016)
			(end 0.3048 -0.1016)
			(stroke
				(width 0.1)
				(type default)
			)
			(layer "B.Fab")
		)
		(fp_line
			(start 0.3048 0.9906)
			(end -0.3048 0.9906)
			(stroke
				(width 0.1)
				(type default)
			)
			(layer "B.Fab")
		)
		(fp_line
			(start -0.3048 0.9906)
			(end -0.3048 -0.1016)
			(stroke
				(width 0.1)
				(type default)
			)
			(layer "B.Fab")
		)
		(pad "1" smd rect
			(at 0 0 270)
			(size 0.508 0.508)
			(layers "B.Cu" "B.Mask" "B.Paste")
			(net "P3E_PCH_M2_TX_C_DP<3>")
		)
		(pad "2" smd rect
			(at 0 0.889 270)
			(size 0.508 0.508)
			(layers "B.Cu" "B.Mask" "B.Paste")
			(net "P3E_PCH_M2_TX_DP<3>")
		)
		(zone
			(layer "B.Cu")
			(hatch none 0.5)
			(connect_pads
				(clearance 0)
			)
			(min_thickness 0.25)
			(keepout
				(tracks allowed)
				(vias not_allowed)
				(pads allowed)
				(copperpour not_allowed)
				(footprints allowed)
			)
			(placement
				(enabled no)
				(sheetname "")
			)
			(fill
				(thermal_gap 0.5)
				(thermal_bridge_width 0.5)
				(island_removal_mode 0)
			)
			(polygon
				(pts
					(xy 385.471924 -25.139904) (xy 385.471924 -24.631904) (xy 385.852924 -24.631904) (xy 385.852924 -25.139904)
				)
			)
		)
		(zone
			(layer "B.Cu")
			(hatch none 0.5)
			(connect_pads
				(clearance 0)
			)
			(min_thickness 0.25)
			(keepout
				(tracks not_allowed)
				(vias allowed)
				(pads allowed)
				(copperpour not_allowed)
				(footprints allowed)
			)
			(placement
				(enabled no)
				(sheetname "")
			)
			(fill
				(thermal_gap 0.5)
				(thermal_bridge_width 0.5)
				(island_removal_mode 0)
			)
			(polygon
				(pts
					(xy 385.852924 -25.139904) (xy 385.852924 -24.631904) (xy 385.471924 -24.631904) (xy 385.471924 -25.139904)
				)
			)
		)
	)
	(footprint ""
		(layer "B.Cu")
		(at 371.05209 -65.411604 180)
		(property "Reference" "R3R15"
			(at 0 0 0)
			(layer "B.SilkS")
			(hide yes)
			(effects
				(font
					(size 1.27 1.27)
				)
				(justify mirror)
			)
		)
		(property "Value" ""
			(at 0 0 0)
			(layer "B.Fab")
			(effects
				(font
					(size 1.27 1.27)
				)
				(justify mirror)
			)
		)
		(duplicate_pad_numbers_are_jumpers no)
		(fp_poly
			(pts
				(xy 0.2794 -0.1016) (xy -0.2794 -0.1016) (xy -0.2794 0.9906) (xy 0.2794 0.9906)
			)
			(stroke
				(width 0)
				(type default)
			)
			(fill no)
			(layer "B.CrtYd")
		)
		(fp_line
			(start 0.2794 0.9906)
			(end -0.2794 0.9906)
			(stroke
				(width 0.1)
				(type default)
			)
			(layer "B.Fab")
		)
		(fp_line
			(start 0.2794 -0.1016)
			(end 0.2794 0.9906)
			(stroke
				(width 0.1)
				(type default)
			)
			(layer "B.Fab")
		)
		(fp_line
			(start -0.2794 0.9906)
			(end -0.2794 -0.1016)
			(stroke
				(width 0.1)
				(type default)
			)
			(layer "B.Fab")
		)
		(fp_line
			(start -0.2794 -0.1016)
			(end 0.2794 -0.1016)
			(stroke
				(width 0.1)
				(type default)
			)
			(layer "B.Fab")
		)
		(pad "1" smd rect
			(at 0 0)
			(size 0.508 0.508)
			(layers "B.Cu" "B.Mask" "B.Paste")
			(net "P3V3_STBY")
		)
		(pad "2" smd rect
			(at 0 0.889)
			(size 0.508 0.508)
			(layers "B.Cu" "B.Mask" "B.Paste")
			(net "FM_JTAG_PLD_EN_DEBUG")
		)
		(zone
			(layer "B.Cu")
			(hatch none 0.5)
			(connect_pads
				(clearance 0)
			)
			(min_thickness 0.25)
			(keepout
				(tracks not_allowed)
				(vias allowed)
				(pads allowed)
				(copperpour not_allowed)
				(footprints allowed)
			)
			(placement
				(enabled no)
				(sheetname "")
			)
			(fill
				(thermal_gap 0.5)
				(thermal_bridge_width 0.5)
				(island_removal_mode 0)
			)
			(polygon
				(pts
					(xy 370.79809 -66.046604) (xy 371.30609 -66.046604) (xy 371.30609 -65.665604) (xy 370.79809 -65.665604)
				)
			)
		)
		(zone
			(layer "B.Cu")
			(hatch none 0.5)
			(connect_pads
				(clearance 0)
			)
			(min_thickness 0.25)
			(keepout
				(tracks allowed)
				(vias not_allowed)
				(pads allowed)
				(copperpour not_allowed)
				(footprints allowed)
			)
			(placement
				(enabled no)
				(sheetname "")
			)
			(fill
				(thermal_gap 0.5)
				(thermal_bridge_width 0.5)
				(island_removal_mode 0)
			)
			(polygon
				(pts
					(xy 370.79809 -65.665604) (xy 371.30609 -65.665604) (xy 371.30609 -66.046604) (xy 370.79809 -66.046604)
				)
			)
		)
	)
	(footprint ""
		(layer "B.Cu")
		(at 276.9362 -29.337 90)
		(property "Reference" "R4U6"
			(at 0 0 90)
			(layer "B.SilkS")
			(hide yes)
			(effects
				(font
					(size 1.27 1.27)
				)
				(justify mirror)
			)
		)
		(property "Value" ""
			(at 0 0 90)
			(layer "B.Fab")
			(effects
				(font
					(size 1.27 1.27)
				)
				(justify mirror)
			)
		)
		(duplicate_pad_numbers_are_jumpers no)
		(fp_rect
			(start -0.2794 0.9906)
			(end 0.2794 -0.1016)
			(stroke
				(width 0)
				(type default)
			)
			(fill no)
			(layer "B.CrtYd")
		)
		(fp_line
			(start 0.2794 -0.1016)
			(end 0.2794 0.9906)
			(stroke
				(width 0.1)
				(type default)
			)
			(layer "B.Fab")
		)
		(fp_line
			(start -0.2794 -0.1016)
			(end 0.2794 -0.1016)
			(stroke
				(width 0.1)
				(type default)
			)
			(layer "B.Fab")
		)
		(fp_line
			(start 0.2794 0.9906)
			(end -0.2794 0.9906)
			(stroke
				(width 0.1)
				(type default)
			)
			(layer "B.Fab")
		)
		(fp_line
			(start -0.2794 0.9906)
			(end -0.2794 -0.1016)
			(stroke
				(width 0.1)
				(type default)
			)
			(layer "B.Fab")
		)
		(pad "1" smd rect
			(at 0 0 270)
			(size 0.508 0.508)
			(layers "B.Cu" "B.Mask" "B.Paste")
			(net "VSENSE_PVDDQ_ABC_P")
		)
		(pad "2" smd rect
			(at 0 0.889 270)
			(size 0.508 0.508)
			(layers "B.Cu" "B.Mask" "B.Paste")
			(net "VSENSE_PVDDQ_ABC_N")
		)
		(zone
			(layer "B.Cu")
			(hatch none 0.5)
			(connect_pads
				(clearance 0)
			)
			(min_thickness 0.25)
			(keepout
				(tracks allowed)
				(vias not_allowed)
				(pads allowed)
				(copperpour not_allowed)
				(footprints allowed)
			)
			(placement
				(enabled no)
				(sheetname "")
			)
			(fill
				(thermal_gap 0.5)
				(thermal_bridge_width 0.5)
				(island_removal_mode 0)
			)
			(polygon
				(pts
					(xy 277.5712 -29.083) (xy 277.5712 -29.591) (xy 277.1902 -29.591) (xy 277.1902 -29.083)
				)
			)
		)
	)
	(footprint ""
		(layer "B.Cu")
		(at 392.382756 -19.68119 180)
		(property "Reference" "R32W7"
			(at 0.8382 -0.67818 180)
			(unlocked yes)
			(layer "B.SilkS")
			(effects
				(font
					(size 0.4064 0.254)
					(thickness 0.1524)
				)
				(justify left mirror)
			)
		)
		(property "Value" ""
			(at 0 0 0)
			(layer "B.Fab")
			(effects
				(font
					(size 1.27 1.27)
				)
				(justify mirror)
			)
		)
		(duplicate_pad_numbers_are_jumpers no)
		(fp_poly
			(pts
				(xy 0.2794 -0.1016) (xy -0.2794 -0.1016) (xy -0.2794 0.9906) (xy 0.2794 0.9906)
			)
			(stroke
				(width 0)
				(type default)
			)
			(fill no)
			(layer "B.CrtYd")
		)
		(fp_line
			(start 0.2794 0.9906)
			(end -0.2794 0.9906)
			(stroke
				(width 0.1)
				(type default)
			)
			(layer "B.Fab")
		)
		(fp_line
			(start 0.2794 -0.1016)
			(end 0.2794 0.9906)
			(stroke
				(width 0.1)
				(type default)
			)
			(layer "B.Fab")
		)
		(fp_line
			(start -0.2794 0.9906)
			(end -0.2794 -0.1016)
			(stroke
				(width 0.1)
				(type default)
			)
			(layer "B.Fab")
		)
		(fp_line
			(start -0.2794 -0.1016)
			(end 0.2794 -0.1016)
			(stroke
				(width 0.1)
				(type default)
			)
			(layer "B.Fab")
		)
		(pad "1" smd rect
			(at 0 0)
			(size 0.508 0.508)
			(layers "B.Cu" "B.Mask" "B.Paste")
			(net "P1V8_M2")
		)
		(pad "2" smd rect
			(at 0 0.889)
			(size 0.508 0.508)
			(layers "B.Cu" "B.Mask" "B.Paste")
			(net "SMB_M2_ALT_N")
		)
		(zone
			(layer "B.Cu")
			(hatch none 0.5)
			(connect_pads
				(clearance 0)
			)
			(min_thickness 0.25)
			(keepout
				(tracks not_allowed)
				(vias allowed)
				(pads allowed)
				(copperpour not_allowed)
				(footprints allowed)
			)
			(placement
				(enabled no)
				(sheetname "")
			)
			(fill
				(thermal_gap 0.5)
				(thermal_bridge_width 0.5)
				(island_removal_mode 0)
			)
			(polygon
				(pts
					(xy 392.128756 -20.31619) (xy 392.636756 -20.31619) (xy 392.636756 -19.93519) (xy 392.128756 -19.93519)
				)
			)
		)
		(zone
			(layer "B.Cu")
			(hatch none 0.5)
			(connect_pads
				(clearance 0)
			)
			(min_thickness 0.25)
			(keepout
				(tracks allowed)
				(vias not_allowed)
				(pads allowed)
				(copperpour not_allowed)
				(footprints allowed)
			)
			(placement
				(enabled no)
				(sheetname "")
			)
			(fill
				(thermal_gap 0.5)
				(thermal_bridge_width 0.5)
				(island_removal_mode 0)
			)
			(polygon
				(pts
					(xy 392.128756 -19.93519) (xy 392.636756 -19.93519) (xy 392.636756 -20.31619) (xy 392.128756 -20.31619)
				)
			)
		)
	)
	(footprint ""
		(layer "B.Cu")
		(at 419.220142 -82.042)
		(property "Reference" "R2P5"
			(at 0 0 0)
			(layer "B.SilkS")
			(hide yes)
			(effects
				(font
					(size 1.27 1.27)
				)
				(justify mirror)
			)
		)
		(property "Value" ""
			(at 0 0 0)
			(layer "B.Fab")
			(effects
				(font
					(size 1.27 1.27)
				)
				(justify mirror)
			)
		)
		(duplicate_pad_numbers_are_jumpers no)
		(fp_poly
			(pts
				(xy 0.2794 -0.1016) (xy -0.2794 -0.1016) (xy -0.2794 0.9906) (xy 0.2794 0.9906)
			)
			(stroke
				(width 0)
				(type default)
			)
			(fill no)
			(layer "B.CrtYd")
		)
		(fp_line
			(start -0.2794 -0.1016)
			(end 0.2794 -0.1016)
			(stroke
				(width 0.1)
				(type default)
			)
			(layer "B.Fab")
		)
		(fp_line
			(start -0.2794 0.9906)
			(end -0.2794 -0.1016)
			(stroke
				(width 0.1)
				(type default)
			)
			(layer "B.Fab")
		)
		(fp_line
			(start 0.2794 -0.1016)
			(end 0.2794 0.9906)
			(stroke
				(width 0.1)
				(type default)
			)
			(layer "B.Fab")
		)
		(fp_line
			(start 0.2794 0.9906)
			(end -0.2794 0.9906)
			(stroke
				(width 0.1)
				(type default)
			)
			(layer "B.Fab")
		)
		(pad "1" smd rect
			(at 0 0 180)
			(size 0.508 0.508)
			(layers "B.Cu" "B.Mask" "B.Paste")
			(net "P3V3_STBY")
		)
		(pad "2" smd rect
			(at 0 0.889 180)
			(size 0.508 0.508)
			(layers "B.Cu" "B.Mask" "B.Paste")
			(net "FM_PMBUS_ALERT_BUF_EN")
		)
		(zone
			(layer "B.Cu")
			(hatch none 0.5)
			(connect_pads
				(clearance 0)
			)
			(min_thickness 0.25)
			(keepout
				(tracks allowed)
				(vias not_allowed)
				(pads allowed)
				(copperpour not_allowed)
				(footprints allowed)
			)
			(placement
				(enabled no)
				(sheetname "")
			)
			(fill
				(thermal_gap 0.5)
				(thermal_bridge_width 0.5)
				(island_removal_mode 0)
			)
			(polygon
				(pts
					(xy 419.474142 -81.788) (xy 418.966142 -81.788) (xy 418.966142 -81.407) (xy 419.474142 -81.407)
				)
			)
		)
		(zone
			(layer "B.Cu")
			(hatch none 0.5)
			(connect_pads
				(clearance 0)
			)
			(min_thickness 0.25)
			(keepout
				(tracks not_allowed)
				(vias allowed)
				(pads allowed)
				(copperpour not_allowed)
				(footprints allowed)
			)
			(placement
				(enabled no)
				(sheetname "")
			)
			(fill
				(thermal_gap 0.5)
				(thermal_bridge_width 0.5)
				(island_removal_mode 0)
			)
			(polygon
				(pts
					(xy 419.474142 -81.407) (xy 418.966142 -81.407) (xy 418.966142 -81.788) (xy 419.474142 -81.788)
				)
			)
		)
	)
	(footprint ""
		(layer "B.Cu")
		(at 193.802 -134.874 180)
		(property "Reference" "R6M1"
			(at 0 0 0)
			(layer "B.SilkS")
			(hide yes)
			(effects
				(font
					(size 1.27 1.27)
				)
				(justify mirror)
			)
		)
		(property "Value" ""
			(at 0 0 0)
			(layer "B.Fab")
			(effects
				(font
					(size 1.27 1.27)
				)
				(justify mirror)
			)
		)
		(duplicate_pad_numbers_are_jumpers no)
		(fp_poly
			(pts
				(xy 0.2794 -0.1016) (xy -0.2794 -0.1016) (xy -0.2794 0.9906) (xy 0.2794 0.9906)
			)
			(stroke
				(width 0)
				(type default)
			)
			(fill no)
			(layer "B.CrtYd")
		)
		(fp_line
			(start 0.2794 0.9906)
			(end -0.2794 0.9906)
			(stroke
				(width 0.1)
				(type default)
			)
			(layer "B.Fab")
		)
		(fp_line
			(start 0.2794 -0.1016)
			(end 0.2794 0.9906)
			(stroke
				(width 0.1)
				(type default)
			)
			(layer "B.Fab")
		)
		(fp_line
			(start -0.2794 0.9906)
			(end -0.2794 -0.1016)
			(stroke
				(width 0.1)
				(type default)
			)
			(layer "B.Fab")
		)
		(fp_line
			(start -0.2794 -0.1016)
			(end 0.2794 -0.1016)
			(stroke
				(width 0.1)
				(type default)
			)
			(layer "B.Fab")
		)
		(pad "1" smd rect
			(at 0 0)
			(size 0.508 0.508)
			(layers "B.Cu" "B.Mask" "B.Paste")
			(net "PVDDQ_DEF")
		)
		(pad "2" smd rect
			(at 0 0.889)
			(size 0.508 0.508)
			(layers "B.Cu" "B.Mask" "B.Paste")
			(net "M_D_VREF")
		)
		(zone
			(layer "B.Cu")
			(hatch none 0.5)
			(connect_pads
				(clearance 0)
			)
			(min_thickness 0.25)
			(keepout
				(tracks not_allowed)
				(vias allowed)
				(pads allowed)
				(copperpour not_allowed)
				(footprints allowed)
			)
			(placement
				(enabled no)
				(sheetname "")
			)
			(fill
				(thermal_gap 0.5)
				(thermal_bridge_width 0.5)
				(island_removal_mode 0)
			)
			(polygon
				(pts
					(xy 193.548 -135.509) (xy 194.056 -135.509) (xy 194.056 -135.128) (xy 193.548 -135.128)
				)
			)
		)
		(zone
			(layer "B.Cu")
			(hatch none 0.5)
			(connect_pads
				(clearance 0)
			)
			(min_thickness 0.25)
			(keepout
				(tracks allowed)
				(vias not_allowed)
				(pads allowed)
				(copperpour not_allowed)
				(footprints allowed)
			)
			(placement
				(enabled no)
				(sheetname "")
			)
			(fill
				(thermal_gap 0.5)
				(thermal_bridge_width 0.5)
				(island_removal_mode 0)
			)
			(polygon
				(pts
					(xy 193.548 -135.128) (xy 194.056 -135.128) (xy 194.056 -135.509) (xy 193.548 -135.509)
				)
			)
		)
	)
)
